# T6G (Grand Teton) — schematic netlist excerpt (pin names and nets, part order shuffled) for the footprints in the layout excerpt that follows; sources: Cadence DE-HDL packaged netlist, KiCad conversion of 04192023_DAF0TMB3IC0_F0TG_MB_C_brd_V02_OCP.brd

R194  Q_RES  0 5% CHIP  pkg 0402LF  page 81 : A = CPU1_SPD_HOST_CTRL_N ; B = CPU1_SPD_HOST_CTRL_R1_N
R6016  Q_RES  2K 5% EMPTY  pkg 0402LF  page 151 : A = P3V3_AUX ; B = SGPIO_SCM_DO_<0>

(kicad_pcb
	(version 20260206)
	(generator "pcbnew")
	(generator_version "10.0")
	(general
		(thickness 1.6)
		(legacy_teardrops no)
	)
	(paper "A4")
	(title_block
		(title "04192023_DAF0TMB3IC0_F0TG_MB_C_brd_V02_OCP.brd")
		(comment 1 "Grand Teton / footprints 7256-7257 of 8354")
	)
	(layers
		(0 "F.Cu" signal "TOP")
		(4 "In1.Cu" signal "GND")
		(6 "In2.Cu" signal "IN1")
		(8 "In3.Cu" signal "GND1")
		(10 "In4.Cu" signal "IN2")
		(12 "In5.Cu" signal "GND2")
		(14 "In6.Cu" signal "IN3")
		(16 "In7.Cu" signal "GND3")
		(18 "In8.Cu" signal "VCC")
		(20 "In9.Cu" signal "VCC1")
		(22 "In10.Cu" signal "GND4")
		(24 "In11.Cu" signal "IN4")
		(26 "In12.Cu" signal "GND5")
		(28 "In13.Cu" signal "IN5")
		(30 "In14.Cu" signal "GND6")
		(32 "In15.Cu" signal "IN6")
		(34 "In16.Cu" signal "GND7")
		(2 "B.Cu" signal "BOTTOM")
		(9 "F.Adhes" user "F.Adhesive")
		(11 "B.Adhes" user "B.Adhesive")
		(13 "F.Paste" user "Package Geometry/Pastemask Top")
		(15 "B.Paste" user "Package Geometry/Pastemask Bottom")
		(5 "F.SilkS" user "Ref Des/Silkscreen Top")
		(7 "B.SilkS" user "Ref Des/Silkscreen Bottom")
		(1 "F.Mask" user "Board Geometry/Soldermask Top")
		(3 "B.Mask" user "Board Geometry/Soldermask Bottom")
		(17 "Dwgs.User" user "User.Drawings")
		(19 "Cmts.User" user "User.Comments")
		(21 "Eco1.User" user "User.Eco1")
		(23 "Eco2.User" user "User.Eco2")
		(25 "Edge.Cuts" user "Board Geometry/Outline")
		(27 "Margin" user)
		(31 "F.CrtYd" user "Package Geometry/Place Bound Top")
		(29 "B.CrtYd" user "Package Geometry/Place Bound Bottom")
		(35 "F.Fab" user "Ref Des/Assembly Top")
		(33 "B.Fab" user "Ref Des/Assembly Bottom")
	)
	(footprint ""
		(layer "B.Cu")
		(at 173.609 -100.294948 -90)
		(property "Reference" "R6016"
			(at 0 0 90)
			(layer "B.SilkS")
			(hide yes)
			(effects
				(font
					(size 1.27 1.27)
				)
				(justify mirror)
			)
		)
		(property "Value" ""
			(at 0 0 90)
			(layer "B.Fab")
			(effects
				(font
					(size 1.27 1.27)
				)
				(justify mirror)
			)
		)
		(duplicate_pad_numbers_are_jumpers no)
		(fp_line
			(start -0.7874 0.4064)
			(end 0.7874 0.4064)
			(stroke
				(width 0.1524)
				(type default)
			)
			(layer "B.SilkS")
		)
		(fp_line
			(start 0.7874 0.4064)
			(end 0.7874 -0.4064)
			(stroke
				(width 0.1524)
				(type default)
			)
			(layer "B.SilkS")
		)
		(fp_line
			(start -0.7874 -0.4064)
			(end -0.7874 0.4064)
			(stroke
				(width 0.1524)
				(type default)
			)
			(layer "B.SilkS")
		)
		(fp_line
			(start 0.7874 -0.4064)
			(end -0.7874 -0.4064)
			(stroke
				(width 0.1524)
				(type default)
			)
			(layer "B.SilkS")
		)
		(fp_line
			(start -0.67945 0.3048)
			(end -0.120396 0.3048)
			(stroke
				(width 0.1)
				(type default)
			)
			(layer "B.Fab")
		)
		(fp_line
			(start -0.120396 0.3048)
			(end -0.120396 0.2794)
			(stroke
				(width 0.1)
				(type default)
			)
			(layer "B.Fab")
		)
		(fp_line
			(start 0.12065 0.3048)
			(end 0.67945 0.3048)
			(stroke
				(width 0.1)
				(type default)
			)
			(layer "B.Fab")
		)
		(fp_line
			(start 0.67945 0.3048)
			(end 0.67945 -0.305054)
			(stroke
				(width 0.1)
				(type default)
			)
			(layer "B.Fab")
		)
		(fp_line
			(start -0.120396 0.2794)
			(end 0.12065 0.2794)
			(stroke
				(width 0.1)
				(type default)
			)
			(layer "B.Fab")
		)
		(fp_line
			(start 0.12065 0.2794)
			(end 0.12065 0.3048)
			(stroke
				(width 0.1)
				(type default)
			)
			(layer "B.Fab")
		)
		(fp_line
			(start -0.12065 -0.2794)
			(end -0.12065 -0.3048)
			(stroke
				(width 0.1)
				(type default)
			)
			(layer "B.Fab")
		)
		(fp_line
			(start 0.12065 -0.2794)
			(end -0.12065 -0.2794)
			(stroke
				(width 0.1)
				(type default)
			)
			(layer "B.Fab")
		)
		(fp_line
			(start -0.67945 -0.3048)
			(end -0.67945 0.3048)
			(stroke
				(width 0.1)
				(type default)
			)
			(layer "B.Fab")
		)
		(fp_line
			(start -0.12065 -0.3048)
			(end -0.67945 -0.3048)
			(stroke
				(width 0.1)
				(type default)
			)
			(layer "B.Fab")
		)
		(fp_line
			(start 0.12065 -0.305054)
			(end 0.12065 -0.2794)
			(stroke
				(width 0.1)
				(type default)
			)
			(layer "B.Fab")
		)
		(fp_line
			(start 0.67945 -0.305054)
			(end 0.12065 -0.305054)
			(stroke
				(width 0.1)
				(type default)
			)
			(layer "B.Fab")
		)
		(pad "1" smd circle
			(at 0.40005 0 90)
			(size 0 0)
			(layers "B.Cu" "B.Mask" "B.Paste")
			(net "P3V3_AUX")
		)
		(pad "2" smd circle
			(at -0.40005 0 90)
			(size 0 0)
			(layers "B.Cu" "B.Mask" "B.Paste")
			(net "SGPIO_SCM_DO_<0>")
		)
	)
	(footprint ""
		(layer "B.Cu")
		(at 188.710824 -136.658096 90)
		(property "Reference" "R194"
			(at 0 0 90)
			(layer "B.SilkS")
			(hide yes)
			(effects
				(font
					(size 1.27 1.27)
				)
				(justify mirror)
			)
		)
		(property "Value" ""
			(at 0 0 90)
			(layer "B.Fab")
			(effects
				(font
					(size 1.27 1.27)
				)
				(justify mirror)
			)
		)
		(duplicate_pad_numbers_are_jumpers no)
		(fp_line
			(start 0.7874 -0.4064)
			(end -0.7874 -0.4064)
			(stroke
				(width 0.1524)
				(type default)
			)
			(layer "B.SilkS")
		)
		(fp_line
			(start -0.7874 -0.4064)
			(end -0.7874 0.4064)
			(stroke
				(width 0.1524)
				(type default)
			)
			(layer "B.SilkS")
		)
		(fp_line
			(start 0.7874 0.4064)
			(end 0.7874 -0.4064)
			(stroke
				(width 0.1524)
				(type default)
			)
			(layer "B.SilkS")
		)
		(fp_line
			(start -0.7874 0.4064)
			(end 0.7874 0.4064)
			(stroke
				(width 0.1524)
				(type default)
			)
			(layer "B.SilkS")
		)
		(fp_line
			(start 0.67945 -0.305054)
			(end 0.12065 -0.305054)
			(stroke
				(width 0.1)
				(type default)
			)
			(layer "B.Fab")
		)
		(fp_line
			(start 0.12065 -0.305054)
			(end 0.12065 -0.2794)
			(stroke
				(width 0.1)
				(type default)
			)
			(layer "B.Fab")
		)
		(fp_line
			(start -0.12065 -0.3048)
			(end -0.67945 -0.3048)
			(stroke
				(width 0.1)
				(type default)
			)
			(layer "B.Fab")
		)
		(fp_line
			(start -0.67945 -0.3048)
			(end -0.67945 0.3048)
			(stroke
				(width 0.1)
				(type default)
			)
			(layer "B.Fab")
		)
		(fp_line
			(start 0.12065 -0.2794)
			(end -0.12065 -0.2794)
			(stroke
				(width 0.1)
				(type default)
			)
			(layer "B.Fab")
		)
		(fp_line
			(start -0.12065 -0.2794)
			(end -0.12065 -0.3048)
			(stroke
				(width 0.1)
				(type default)
			)
			(layer "B.Fab")
		)
		(fp_line
			(start 0.12065 0.2794)
			(end 0.12065 0.3048)
			(stroke
				(width 0.1)
				(type default)
			)
			(layer "B.Fab")
		)
		(fp_line
			(start -0.120396 0.2794)
			(end 0.12065 0.2794)
			(stroke
				(width 0.1)
				(type default)
			)
			(layer "B.Fab")
		)
		(fp_line
			(start 0.67945 0.3048)
			(end 0.67945 -0.305054)
			(stroke
				(width 0.1)
				(type default)
			)
			(layer "B.Fab")
		)
		(fp_line
			(start 0.12065 0.3048)
			(end 0.67945 0.3048)
			(stroke
				(width 0.1)
				(type default)
			)
			(layer "B.Fab")
		)
		(fp_line
			(start -0.120396 0.3048)
			(end -0.120396 0.2794)
			(stroke
				(width 0.1)
				(type default)
			)
			(layer "B.Fab")
		)
		(fp_line
			(start -0.67945 0.3048)
			(end -0.120396 0.3048)
			(stroke
				(width 0.1)
				(type default)
			)
			(layer "B.Fab")
		)
		(pad "1" smd circle
			(at 0.40005 0 270)
			(size 0 0)
			(layers "B.Cu" "B.Mask" "B.Paste")
			(net "CPU1_SPD_HOST_CTRL_N")
		)
		(pad "2" smd circle
			(at -0.40005 0 270)
			(size 0 0)
			(layers "B.Cu" "B.Mask" "B.Paste")
			(net "CPU1_SPD_HOST_CTRL_R1_N")
		)
	)
)
